(kicad_pcb
	(version 20260206)
	(generator "pcbnew")
	(generator_version "10.0")
	(general
		(thickness 1.6)
		(legacy_teardrops no)
	)
	(paper "A4")
	(title_block
		(title "panther-plus-userver — 13130-1b_20150205.brd")
		(comment 1 "Honey Badger (Wiwynn) / footprint 624 of 1509 (DIMM4), pads 86-92 of 210")
	)
	(layers
		(0 "F.Cu" signal "TOP")
		(4 "In1.Cu" signal "L2")
		(6 "In2.Cu" signal "L3")
		(8 "In3.Cu" signal "L4")
		(10 "In4.Cu" signal "L5")
		(12 "In5.Cu" signal "L6")
		(14 "In6.Cu" signal "L7")
		(16 "In7.Cu" signal "L8")
		(18 "In8.Cu" signal "L9")
		(20 "In9.Cu" signal "L10")
		(22 "In10.Cu" signal "L11")
		(2 "B.Cu" signal "BOTTOM")
		(9 "F.Adhes" user "F.Adhesive")
		(11 "B.Adhes" user "B.Adhesive")
		(13 "F.Paste" user "Package Geometry/Pastemask Top")
		(15 "B.Paste" user "Package Geometry/Pastemask Bottom")
		(5 "F.SilkS" user "Ref Des/Silkscreen Top")
		(7 "B.SilkS" user "Ref Des/Silkscreen Bottom")
		(1 "F.Mask" user "Board Geometry/Soldermask Top")
		(3 "B.Mask" user "Board Geometry/Soldermask Bottom")
		(17 "Dwgs.User" user "User.Drawings")
		(19 "Cmts.User" user "User.Comments")
		(21 "Eco1.User" user "User.Eco1")
		(23 "Eco2.User" user "User.Eco2")
		(25 "Edge.Cuts" user "Board Geometry/Outline")
		(27 "Margin" user)
		(31 "F.CrtYd" user "Package Geometry/Place Bound Top")
		(29 "B.CrtYd" user "Package Geometry/Place Bound Bottom")
		(35 "F.Fab" user "Ref Des/Assembly Top")
		(33 "B.Fab" user "Ref Des/Assembly Bottom")
	)
	(footprint ""
		(layer "F.Cu")
		(at 159.999934 -5.790692)
		(property "Reference" "DIMM4"
			(at 0 0 0)
			(layer "F.SilkS")
			(hide yes)
			(effects
				(font
					(size 1.27 1.27)
				)
			)
		)
		(property "Value" "DDR3-204P-174-COLAY-1-GP"
			(at -40.682164 -17.468088 0)
			(unlocked yes)
			(layer "F.Fab")
			(hide yes)
			(effects
				(font
					(size 1.016 1.016)
					(thickness 0.1524)
				)
			)
		)
		(property "Device Type" "AS0A626-H8SN-7H-COLAY-1"
			(at -40.682164 -18.992088 0)
			(unlocked yes)
			(layer "F.Fab")
			(hide yes)
			(effects
				(font
					(size 1.016 1.016)
					(thickness 0.1524)
				)
			)
		)
		(duplicate_pad_numbers_are_jumpers no)
		(pad "84" smd custom
			(at -4.350004 -4.106672)
			(size 0.1143 0.1143)
			(layers "F.Cu" "F.Mask" "F.Paste")
			(net "DDR3_M_B_VREF_CA")
			(options
				(clearance outline)
				(anchor circle)
			)
			(primitives
				(gr_poly
					(pts
						(xy 0 0.9017) (xy -0.03175 0.89916) (xy -0.0635 0.889) (xy -0.09144 0.87376) (xy -0.11684 0.85344)
						(xy -0.13716 0.82804) (xy -0.1524 0.8001) (xy -0.16256 0.76835) (xy -0.1651 0.7366) (xy -0.1651 0.19685)
						(xy -0.17272 0.18923) (xy -0.17907 0.18034) (xy -0.18669 0.17145) (xy -0.19177 0.16256) (xy -0.19812 0.15367)
						(xy -0.20828 0.13335) (xy -0.21971 0.10287) (xy -0.22225 0.09271) (xy -0.22479 0.08128) (xy -0.22606 0.07112)
						(xy -0.2286 0.05969) (xy -0.2286 0.01651) (xy -0.22606 0.00508) (xy -0.22479 -0.00508) (xy -0.22225 -0.01651)
						(xy -0.21971 -0.02667) (xy -0.20828 -0.05715) (xy -0.19812 -0.07747) (xy -0.19177 -0.08636) (xy -0.18669 -0.09525)
						(xy -0.17907 -0.10414) (xy -0.17272 -0.11303) (xy -0.1651 -0.12065) (xy -0.1651 -0.7366) (xy -0.16256 -0.76835)
						(xy -0.1524 -0.8001) (xy -0.13716 -0.82804) (xy -0.11684 -0.85344) (xy -0.09144 -0.87376) (xy -0.0635 -0.889)
						(xy -0.03175 -0.89916) (xy 0 -0.9017) (xy 0.03175 -0.89916) (xy 0.0635 -0.889) (xy 0.09144 -0.87376)
						(xy 0.11684 -0.85344) (xy 0.13716 -0.82804) (xy 0.1524 -0.8001) (xy 0.16256 -0.76835) (xy 0.1651 -0.7366)
						(xy 0.1651 -0.11938) (xy 0.17272 -0.11176) (xy 0.19812 -0.0762) (xy 0.2032 -0.06604) (xy 0.20701 -0.05715)
						(xy 0.21209 -0.04699) (xy 0.2159 -0.03683) (xy 0.21844 -0.02667) (xy 0.22225 -0.01524) (xy 0.22352 -0.00508)
						(xy 0.22606 0.00508) (xy 0.22733 0.01651) (xy 0.22733 0.02667) (xy 0.2286 0.0381) (xy 0.22733 0.04953)
						(xy 0.22733 0.05969) (xy 0.22606 0.07112) (xy 0.22352 0.08128) (xy 0.22225 0.09144) (xy 0.21844 0.10287)
						(xy 0.2159 0.11303) (xy 0.21209 0.12319) (xy 0.20701 0.13335) (xy 0.2032 0.14224) (xy 0.19812 0.1524)
						(xy 0.17272 0.18796) (xy 0.1651 0.19558) (xy 0.1651 0.7366) (xy 0.16256 0.76835) (xy 0.1524 0.8001)
						(xy 0.13716 0.82804) (xy 0.11684 0.85344) (xy 0.09144 0.87376) (xy 0.0635 0.889) (xy 0.03175 0.89916)
					)
					(width 0)
					(fill yes)
				)
			)
		)
		(pad "85" smd custom
			(at -4.05003 4.106672)
			(size 0.1143 0.1143)
			(layers "F.Cu" "F.Mask" "F.Paste")
			(net "PV_VDDR")
			(options
				(clearance outline)
				(anchor circle)
			)
			(primitives
				(gr_poly
					(pts
						(xy 0 0.9017) (xy -0.03175 0.89916) (xy -0.0635 0.889) (xy -0.09144 0.87376) (xy -0.11684 0.85344)
						(xy -0.13716 0.82804) (xy -0.1524 0.8001) (xy -0.16256 0.76835) (xy -0.1651 0.7366) (xy -0.1651 -0.13462)
						(xy -0.17272 -0.14224) (xy -0.19812 -0.1778) (xy -0.2032 -0.18796) (xy -0.20701 -0.19685) (xy -0.21209 -0.20701)
						(xy -0.2159 -0.21717) (xy -0.21844 -0.22733) (xy -0.22225 -0.23876) (xy -0.22352 -0.24892) (xy -0.22606 -0.25908)
						(xy -0.22733 -0.27051) (xy -0.22733 -0.28067) (xy -0.2286 -0.2921) (xy -0.22733 -0.30353) (xy -0.22733 -0.31369)
						(xy -0.22606 -0.32512) (xy -0.22352 -0.33528) (xy -0.22225 -0.34544) (xy -0.21844 -0.35687) (xy -0.2159 -0.36703)
						(xy -0.21209 -0.37719) (xy -0.20701 -0.38735) (xy -0.2032 -0.39624) (xy -0.19812 -0.4064) (xy -0.17272 -0.44196)
						(xy -0.1651 -0.44958) (xy -0.1651 -0.7366) (xy -0.16256 -0.76835) (xy -0.1524 -0.8001) (xy -0.13716 -0.82804)
						(xy -0.11684 -0.85344) (xy -0.09144 -0.87376) (xy -0.0635 -0.889) (xy -0.03175 -0.89916) (xy 0 -0.9017)
						(xy 0.03175 -0.89916) (xy 0.0635 -0.889) (xy 0.09144 -0.87376) (xy 0.11684 -0.85344) (xy 0.13716 -0.82804)
						(xy 0.1524 -0.8001) (xy 0.16256 -0.76835) (xy 0.1651 -0.7366) (xy 0.1651 -0.44958) (xy 0.17272 -0.44196)
						(xy 0.19812 -0.4064) (xy 0.2032 -0.39624) (xy 0.20701 -0.38735) (xy 0.21209 -0.37719) (xy 0.2159 -0.36703)
						(xy 0.21844 -0.35687) (xy 0.22225 -0.34544) (xy 0.22352 -0.33528) (xy 0.22606 -0.32512) (xy 0.22733 -0.31369)
						(xy 0.22733 -0.30353) (xy 0.2286 -0.2921) (xy 0.22733 -0.28067) (xy 0.22733 -0.27051) (xy 0.22606 -0.25908)
						(xy 0.22352 -0.24892) (xy 0.22225 -0.23876) (xy 0.21844 -0.22733) (xy 0.2159 -0.21717) (xy 0.21209 -0.20701)
						(xy 0.20701 -0.19685) (xy 0.2032 -0.18796) (xy 0.19812 -0.1778) (xy 0.17272 -0.14224) (xy 0.1651 -0.13462)
						(xy 0.1651 0.7366) (xy 0.16256 0.76835) (xy 0.1524 0.8001) (xy 0.13716 0.82804) (xy 0.11684 0.85344)
						(xy 0.09144 0.87376) (xy 0.0635 0.889) (xy 0.03175 0.89916)
					)
					(width 0)
					(fill yes)
				)
			)
		)
		(pad "86" smd custom
			(at -3.750056 -4.106672)
			(size 0.1143 0.1143)
			(layers "F.Cu" "F.Mask" "F.Paste")
			(net "PV_VDDR")
			(options
				(clearance outline)
				(anchor circle)
			)
			(primitives
				(gr_poly
					(pts
						(xy 0 0.9017) (xy -0.03175 0.89916) (xy -0.0635 0.889) (xy -0.09144 0.87376) (xy -0.11684 0.85344)
						(xy -0.13716 0.82804) (xy -0.1524 0.8001) (xy -0.16256 0.76835) (xy -0.1651 0.7366) (xy -0.1651 0.44958)
						(xy -0.17272 0.44196) (xy -0.19812 0.4064) (xy -0.2032 0.39624) (xy -0.20701 0.38735) (xy -0.21209 0.37719)
						(xy -0.2159 0.36703) (xy -0.21844 0.35687) (xy -0.22225 0.34544) (xy -0.22352 0.33528) (xy -0.22606 0.32512)
						(xy -0.22733 0.31369) (xy -0.22733 0.30353) (xy -0.2286 0.2921) (xy -0.22733 0.28067) (xy -0.22733 0.27051)
						(xy -0.22606 0.25908) (xy -0.22352 0.24892) (xy -0.22225 0.23876) (xy -0.21844 0.22733) (xy -0.2159 0.21717)
						(xy -0.21209 0.20701) (xy -0.20701 0.19685) (xy -0.2032 0.18796) (xy -0.19812 0.1778) (xy -0.17272 0.14224)
						(xy -0.1651 0.13462) (xy -0.1651 -0.7366) (xy -0.16256 -0.76835) (xy -0.1524 -0.8001) (xy -0.13716 -0.82804)
						(xy -0.11684 -0.85344) (xy -0.09144 -0.87376) (xy -0.0635 -0.889) (xy -0.03175 -0.89916) (xy 0 -0.9017)
						(xy 0.03175 -0.89916) (xy 0.0635 -0.889) (xy 0.09144 -0.87376) (xy 0.11684 -0.85344) (xy 0.13716 -0.82804)
						(xy 0.1524 -0.8001) (xy 0.16256 -0.76835) (xy 0.1651 -0.7366) (xy 0.1651 0.13462) (xy 0.17272 0.14224)
						(xy 0.19812 0.1778) (xy 0.2032 0.18796) (xy 0.20701 0.19685) (xy 0.21209 0.20701) (xy 0.2159 0.21717)
						(xy 0.21844 0.22733) (xy 0.22225 0.23876) (xy 0.22352 0.24892) (xy 0.22606 0.25908) (xy 0.22733 0.27051)
						(xy 0.22733 0.28067) (xy 0.2286 0.2921) (xy 0.22733 0.30353) (xy 0.22733 0.31369) (xy 0.22606 0.32512)
						(xy 0.22352 0.33528) (xy 0.22225 0.34544) (xy 0.21844 0.35687) (xy 0.2159 0.36703) (xy 0.21209 0.37719)
						(xy 0.20701 0.38735) (xy 0.2032 0.39624) (xy 0.19812 0.4064) (xy 0.17272 0.44196) (xy 0.1651 0.44958)
						(xy 0.1651 0.7366) (xy 0.16256 0.76835) (xy 0.1524 0.8001) (xy 0.13716 0.82804) (xy 0.11684 0.85344)
						(xy 0.09144 0.87376) (xy 0.0635 0.889) (xy 0.03175 0.89916)
					)
					(width 0)
					(fill yes)
				)
			)
		)
		(pad "87" smd custom
			(at -3.450082 4.106672)
			(size 0.1143 0.1143)
			(layers "F.Cu" "F.Mask" "F.Paste")
			(net "M_B_CKE2")
			(options
				(clearance outline)
				(anchor circle)
			)
			(primitives
				(gr_poly
					(pts
						(xy 0 0.9017) (xy -0.03175 0.89916) (xy -0.0635 0.889) (xy -0.09144 0.87376) (xy -0.11684 0.85344)
						(xy -0.13716 0.82804) (xy -0.1524 0.8001) (xy -0.16256 0.76835) (xy -0.1651 0.7366) (xy -0.1651 0.11938)
						(xy -0.17272 0.11176) (xy -0.19812 0.0762) (xy -0.2032 0.06604) (xy -0.20701 0.05715) (xy -0.21209 0.04699)
						(xy -0.2159 0.03683) (xy -0.21844 0.02667) (xy -0.22225 0.01524) (xy -0.22352 0.00508) (xy -0.22606 -0.00508)
						(xy -0.22733 -0.01651) (xy -0.22733 -0.02667) (xy -0.2286 -0.0381) (xy -0.22733 -0.04953) (xy -0.22733 -0.05969)
						(xy -0.22606 -0.07112) (xy -0.22352 -0.08128) (xy -0.22225 -0.09144) (xy -0.21844 -0.10287) (xy -0.2159 -0.11303)
						(xy -0.21209 -0.12319) (xy -0.20701 -0.13335) (xy -0.2032 -0.14224) (xy -0.19812 -0.1524) (xy -0.17272 -0.18796)
						(xy -0.1651 -0.19558) (xy -0.1651 -0.7366) (xy -0.16256 -0.76835) (xy -0.1524 -0.8001) (xy -0.13716 -0.82804)
						(xy -0.11684 -0.85344) (xy -0.09144 -0.87376) (xy -0.0635 -0.889) (xy -0.03175 -0.89916) (xy 0 -0.9017)
						(xy 0.03175 -0.89916) (xy 0.0635 -0.889) (xy 0.09144 -0.87376) (xy 0.11684 -0.85344) (xy 0.13716 -0.82804)
						(xy 0.1524 -0.8001) (xy 0.16256 -0.76835) (xy 0.1651 -0.7366) (xy 0.1651 -0.19685) (xy 0.17272 -0.18923)
						(xy 0.17907 -0.18034) (xy 0.18669 -0.17145) (xy 0.19177 -0.16256) (xy 0.19812 -0.15367) (xy 0.20828 -0.13335)
						(xy 0.21971 -0.10287) (xy 0.22225 -0.09271) (xy 0.22479 -0.08128) (xy 0.22606 -0.07112) (xy 0.2286 -0.05969)
						(xy 0.2286 -0.01651) (xy 0.22606 -0.00508) (xy 0.22479 0.00508) (xy 0.22225 0.01651) (xy 0.21971 0.02667)
						(xy 0.20828 0.05715) (xy 0.19812 0.07747) (xy 0.19177 0.08636) (xy 0.18669 0.09525) (xy 0.17907 0.10414)
						(xy 0.17272 0.11303) (xy 0.1651 0.12065) (xy 0.1651 0.7366) (xy 0.16256 0.76835) (xy 0.1524 0.8001)
						(xy 0.13716 0.82804) (xy 0.11684 0.85344) (xy 0.09144 0.87376) (xy 0.0635 0.889) (xy 0.03175 0.89916)
					)
					(width 0)
					(fill yes)
				)
			)
		)
		(pad "88" smd custom
			(at -3.150108 -4.106672)
			(size 0.1143 0.1143)
			(layers "F.Cu" "F.Mask" "F.Paste")
			(net "M_B_MA15")
			(options
				(clearance outline)
				(anchor circle)
			)
			(primitives
				(gr_poly
					(pts
						(xy 0 0.9017) (xy -0.03175 0.89916) (xy -0.0635 0.889) (xy -0.09144 0.87376) (xy -0.11684 0.85344)
						(xy -0.13716 0.82804) (xy -0.1524 0.8001) (xy -0.16256 0.76835) (xy -0.1651 0.7366) (xy -0.1651 0.19685)
						(xy -0.17272 0.18923) (xy -0.17907 0.18034) (xy -0.18669 0.17145) (xy -0.19177 0.16256) (xy -0.19812 0.15367)
						(xy -0.20828 0.13335) (xy -0.21971 0.10287) (xy -0.22225 0.09271) (xy -0.22479 0.08128) (xy -0.22606 0.07112)
						(xy -0.2286 0.05969) (xy -0.2286 0.01651) (xy -0.22606 0.00508) (xy -0.22479 -0.00508) (xy -0.22225 -0.01651)
						(xy -0.21971 -0.02667) (xy -0.20828 -0.05715) (xy -0.19812 -0.07747) (xy -0.19177 -0.08636) (xy -0.18669 -0.09525)
						(xy -0.17907 -0.10414) (xy -0.17272 -0.11303) (xy -0.1651 -0.12065) (xy -0.1651 -0.7366) (xy -0.16256 -0.76835)
						(xy -0.1524 -0.8001) (xy -0.13716 -0.82804) (xy -0.11684 -0.85344) (xy -0.09144 -0.87376) (xy -0.0635 -0.889)
						(xy -0.03175 -0.89916) (xy 0 -0.9017) (xy 0.03175 -0.89916) (xy 0.0635 -0.889) (xy 0.09144 -0.87376)
						(xy 0.11684 -0.85344) (xy 0.13716 -0.82804) (xy 0.1524 -0.8001) (xy 0.16256 -0.76835) (xy 0.1651 -0.7366)
						(xy 0.1651 -0.11938) (xy 0.17272 -0.11176) (xy 0.19812 -0.0762) (xy 0.2032 -0.06604) (xy 0.20701 -0.05715)
						(xy 0.21209 -0.04699) (xy 0.2159 -0.03683) (xy 0.21844 -0.02667) (xy 0.22225 -0.01524) (xy 0.22352 -0.00508)
						(xy 0.22606 0.00508) (xy 0.22733 0.01651) (xy 0.22733 0.02667) (xy 0.2286 0.0381) (xy 0.22733 0.04953)
						(xy 0.22733 0.05969) (xy 0.22606 0.07112) (xy 0.22352 0.08128) (xy 0.22225 0.09144) (xy 0.21844 0.10287)
						(xy 0.2159 0.11303) (xy 0.21209 0.12319) (xy 0.20701 0.13335) (xy 0.2032 0.14224) (xy 0.19812 0.1524)
						(xy 0.17272 0.18796) (xy 0.1651 0.19558) (xy 0.1651 0.7366) (xy 0.16256 0.76835) (xy 0.1524 0.8001)
						(xy 0.13716 0.82804) (xy 0.11684 0.85344) (xy 0.09144 0.87376) (xy 0.0635 0.889) (xy 0.03175 0.89916)
					)
					(width 0)
					(fill yes)
				)
			)
		)
		(pad "89" smd custom
			(at -2.84988 4.106672)
			(size 0.1143 0.1143)
			(layers "F.Cu" "F.Mask" "F.Paste")
			(net "M_B_CKE3")
			(options
				(clearance outline)
				(anchor circle)
			)
			(primitives
				(gr_poly
					(pts
						(xy 0 0.9017) (xy -0.03175 0.89916) (xy -0.0635 0.889) (xy -0.09144 0.87376) (xy -0.11684 0.85344)
						(xy -0.13716 0.82804) (xy -0.1524 0.8001) (xy -0.16256 0.76835) (xy -0.1651 0.7366) (xy -0.1651 -0.13462)
						(xy -0.17272 -0.14224) (xy -0.19812 -0.1778) (xy -0.2032 -0.18796) (xy -0.20701 -0.19685) (xy -0.21209 -0.20701)
						(xy -0.2159 -0.21717) (xy -0.21844 -0.22733) (xy -0.22225 -0.23876) (xy -0.22352 -0.24892) (xy -0.22606 -0.25908)
						(xy -0.22733 -0.27051) (xy -0.22733 -0.28067) (xy -0.2286 -0.2921) (xy -0.22733 -0.30353) (xy -0.22733 -0.31369)
						(xy -0.22606 -0.32512) (xy -0.22352 -0.33528) (xy -0.22225 -0.34544) (xy -0.21844 -0.35687) (xy -0.2159 -0.36703)
						(xy -0.21209 -0.37719) (xy -0.20701 -0.38735) (xy -0.2032 -0.39624) (xy -0.19812 -0.4064) (xy -0.17272 -0.44196)
						(xy -0.1651 -0.44958) (xy -0.1651 -0.7366) (xy -0.16256 -0.76835) (xy -0.1524 -0.8001) (xy -0.13716 -0.82804)
						(xy -0.11684 -0.85344) (xy -0.09144 -0.87376) (xy -0.0635 -0.889) (xy -0.03175 -0.89916) (xy 0 -0.9017)
						(xy 0.03175 -0.89916) (xy 0.0635 -0.889) (xy 0.09144 -0.87376) (xy 0.11684 -0.85344) (xy 0.13716 -0.82804)
						(xy 0.1524 -0.8001) (xy 0.16256 -0.76835) (xy 0.1651 -0.7366) (xy 0.1651 -0.44958) (xy 0.17272 -0.44196)
						(xy 0.19812 -0.4064) (xy 0.2032 -0.39624) (xy 0.20701 -0.38735) (xy 0.21209 -0.37719) (xy 0.2159 -0.36703)
						(xy 0.21844 -0.35687) (xy 0.22225 -0.34544) (xy 0.22352 -0.33528) (xy 0.22606 -0.32512) (xy 0.22733 -0.31369)
						(xy 0.22733 -0.30353) (xy 0.2286 -0.2921) (xy 0.22733 -0.28067) (xy 0.22733 -0.27051) (xy 0.22606 -0.25908)
						(xy 0.22352 -0.24892) (xy 0.22225 -0.23876) (xy 0.21844 -0.22733) (xy 0.2159 -0.21717) (xy 0.21209 -0.20701)
						(xy 0.20701 -0.19685) (xy 0.2032 -0.18796) (xy 0.19812 -0.1778) (xy 0.17272 -0.14224) (xy 0.1651 -0.13462)
						(xy 0.1651 0.7366) (xy 0.16256 0.76835) (xy 0.1524 0.8001) (xy 0.13716 0.82804) (xy 0.11684 0.85344)
						(xy 0.09144 0.87376) (xy 0.0635 0.889) (xy 0.03175 0.89916)
					)
					(width 0)
					(fill yes)
				)
			)
		)
		(pad "90" smd custom
			(at -2.549906 -4.106672)
			(size 0.1143 0.1143)
			(layers "F.Cu" "F.Mask" "F.Paste")
			(net "M_B_MA14")
			(options
				(clearance outline)
				(anchor circle)
			)
			(primitives
				(gr_poly
					(pts
						(xy 0 0.9017) (xy -0.03175 0.89916) (xy -0.0635 0.889) (xy -0.09144 0.87376) (xy -0.11684 0.85344)
						(xy -0.13716 0.82804) (xy -0.1524 0.8001) (xy -0.16256 0.76835) (xy -0.1651 0.7366) (xy -0.1651 0.44958)
						(xy -0.17272 0.44196) (xy -0.19812 0.4064) (xy -0.2032 0.39624) (xy -0.20701 0.38735) (xy -0.21209 0.37719)
						(xy -0.2159 0.36703) (xy -0.21844 0.35687) (xy -0.22225 0.34544) (xy -0.22352 0.33528) (xy -0.22606 0.32512)
						(xy -0.22733 0.31369) (xy -0.22733 0.30353) (xy -0.2286 0.2921) (xy -0.22733 0.28067) (xy -0.22733 0.27051)
						(xy -0.22606 0.25908) (xy -0.22352 0.24892) (xy -0.22225 0.23876) (xy -0.21844 0.22733) (xy -0.2159 0.21717)
						(xy -0.21209 0.20701) (xy -0.20701 0.19685) (xy -0.2032 0.18796) (xy -0.19812 0.1778) (xy -0.17272 0.14224)
						(xy -0.1651 0.13462) (xy -0.1651 -0.7366) (xy -0.16256 -0.76835) (xy -0.1524 -0.8001) (xy -0.13716 -0.82804)
						(xy -0.11684 -0.85344) (xy -0.09144 -0.87376) (xy -0.0635 -0.889) (xy -0.03175 -0.89916) (xy 0 -0.9017)
						(xy 0.03175 -0.89916) (xy 0.0635 -0.889) (xy 0.09144 -0.87376) (xy 0.11684 -0.85344) (xy 0.13716 -0.82804)
						(xy 0.1524 -0.8001) (xy 0.16256 -0.76835) (xy 0.1651 -0.7366) (xy 0.1651 0.13462) (xy 0.17272 0.14224)
						(xy 0.19812 0.1778) (xy 0.2032 0.18796) (xy 0.20701 0.19685) (xy 0.21209 0.20701) (xy 0.2159 0.21717)
						(xy 0.21844 0.22733) (xy 0.22225 0.23876) (xy 0.22352 0.24892) (xy 0.22606 0.25908) (xy 0.22733 0.27051)
						(xy 0.22733 0.28067) (xy 0.2286 0.2921) (xy 0.22733 0.30353) (xy 0.22733 0.31369) (xy 0.22606 0.32512)
						(xy 0.22352 0.33528) (xy 0.22225 0.34544) (xy 0.21844 0.35687) (xy 0.2159 0.36703) (xy 0.21209 0.37719)
						(xy 0.20701 0.38735) (xy 0.2032 0.39624) (xy 0.19812 0.4064) (xy 0.17272 0.44196) (xy 0.1651 0.44958)
						(xy 0.1651 0.7366) (xy 0.16256 0.76835) (xy 0.1524 0.8001) (xy 0.13716 0.82804) (xy 0.11684 0.85344)
						(xy 0.09144 0.87376) (xy 0.0635 0.889) (xy 0.03175 0.89916)
					)
					(width 0)
					(fill yes)
				)
			)
		)
	)
)
